#ISCELL
  logical_power design_note *
  *
#ISCELL
  mstr_misc dns *
  *
#ISCELL
  pure_quanta quanta_title_block_c *
  *
#ISCELL
  standard offpage *
  page30_i104
#ISCELL
  standard offpage *
  page30_i105
#ISCELL
  standard offpage *
  page30_i107
#ISCELL
  standard offpage *
  page30_i108
#ISCELL
  logical_power universal_gnd *
  page30_i117
#ISCELL
  standard offpage *
  page30_i142
#ISCELL
  standard offpage *
  page30_i143
#CELL
  pure_quanta q_res *
  page30_i146
#CELL
  pure_quanta q_res *
  page30_i147
#CELL
  pure_quanta q_res *
  page30_i148
#CELL
  pure_quanta q_cap *
  page30_i151
#ISCELL
  logical_power universal_gnd *
  page30_i152
#ISCELL
  logical_power universal_gnd *
  page30_i154
#ISCELL
  standard offpage *
  page30_i172
#ISCELL
  standard offpage *
  page30_i173
#ISCELL
  standard offpage *
  page30_i175
#ISCELL
  standard offpage *
  page30_i176
#ISCELL
  standard offpage *
  page30_i179
#ISCELL
  standard offpage *
  page30_i181
#ISCELL
  logical_power universal_gnd *
  page30_i182
#CELL
  pure_quanta sconn3_21291035br2 *
  page30_i184
#CELL
  pure_quanta q_res *
  page30_i192
#CELL
  pure_quanta q_res *
  page30_i195
#CELL
  pure_quanta q_res *
  page30_i197
#ISCELL
  logical_power universal_power *
  page30_i207
#ISCELL
  logical_power universal_power *
  page30_i208
#ISCELL
  logical_power universal_power *
  page30_i211
#ISCELL
  logical_power universal_power *
  page30_i214
#ISCELL
  logical_power universal_power *
  page30_i217
#ISCELL
  standard offpage *
  page30_i219
#ISCELL
  standard offpage *
  page30_i220
#CELL
  pure_quanta q_res *
  page30_i221
#CELL
  pure_quanta q_res *
  page30_i225
#CELL
  pure_quanta q_res *
  page30_i226
#ISCELL
  logical_power universal_power *
  page30_i227
#ISCELL
  logical_power universal_gnd *
  page30_i228
#CELL
  pure_quanta q_cap *
  page30_i229
#ISCELL
  logical_power universal_power *
  page30_i230
#CELL
  pure_quanta q_res *
  page30_i231
#ISCELL
  logical_power universal_gnd *
  page30_i233
#ISCELL
  standard offpage *
  page30_i234
#ISCELL
  standard offpage *
  page30_i235
#ISCELL
  logical_power universal_power *
  page30_i236
#CELL
  pure_quanta q_res *
  page30_i237
#ISCELL
  logical_power universal_power *
  page30_i238
#CELL
  pure_quanta q_res *
  page30_i239
#CELL
  pure_quanta 74lvc2g07dw7 *
  page30_i246
#CELL
  pure_quanta 74lvc2g07dw7 *
  page30_i247
#CELL
  pure_quanta fsa3357k8x *
  page30_i250
#CELL
  pure_quanta fsa3357k8x *
  page30_i251
#ISCELL
  standard offpage *
  page30_i252
#ISCELL
  logical_power universal_gnd *
  page30_i253
#CELL
  pure_quanta q_cap *
  page30_i254
#ISCELL
  logical_power universal_power *
  page30_i255
#ISCELL
  logical_power universal_gnd *
  page30_i256
#ISCELL
  standard offpage *
  page30_i258
#ISCELL
  standard offpage *
  page30_i259
#ISCELL
  logical_power universal_power *
  page30_i260
#CELL
  pure_quanta q_cap *
  page30_i261
#ISCELL
  logical_power universal_gnd *
  page30_i262
#ISCELL
  standard offpage *
  page30_i263
#ISCELL
  standard offpage *
  page30_i264
#ISCELL
  standard offpage *
  page30_i265
#CELL
  pure_quanta q_res *
  page30_i266
#CELL
  pure_quanta q_res *
  page30_i267
